(kicad_pcb
	(version 20260206)
	(generator "pcbnew")
	(generator_version "10.0")
	(general
		(thickness 1.21888)
		(legacy_teardrops no)
	)
	(paper "A4")
	(title_block
		(title "timecard-v8 — TimeCard-DC-V8_EXP.PcbDoc")
		(comment 1 "Time Appliance Project (Time Card) / footprints 7-9 of 288")
	)
	(layers
		(0 "F.Cu" signal "TOP")
		(4 "In1.Cu" signal "SGND")
		(6 "In2.Cu" signal "IN1")
		(8 "In3.Cu" signal "IN2")
		(10 "In4.Cu" signal "SGND1")
		(2 "B.Cu" signal "BOTTOM")
		(9 "F.Adhes" user "F.Adhesive")
		(11 "B.Adhes" user "B.Adhesive")
		(13 "F.Paste" user "Top Paste")
		(15 "B.Paste" user "Bottom Paste")
		(5 "F.SilkS" user "Top Overlay")
		(7 "B.SilkS" user "Bottom Overlay")
		(1 "F.Mask" user "Top Solder")
		(3 "B.Mask" user "Bottom Solder")
		(17 "Dwgs.User" user "User.Drawings")
		(19 "Cmts.User" user "User.Comments")
		(21 "Eco1.User" user "User.Eco1")
		(23 "Eco2.User" user "User.Eco2")
		(25 "Edge.Cuts" user)
		(27 "Margin" user)
		(31 "F.CrtYd" user "Top Courtyard")
		(29 "B.CrtYd" user "Bottom Courtyard")
		(35 "F.Fab" user "Top Component Center")
		(33 "B.Fab" user "Bottom Component Center")
	)
	(footprint "FPGA_CONN:SingleFPGAConn"
		(layer "F.Cu")
		(at 162.57841 95.87725 -90)
		(property "Reference" "J35"
			(at -0.39436 -23.455129 270)
			(unlocked yes)
			(layer "F.SilkS")
			(effects
				(font
					(size 0.762 0.762)
					(thickness 0.2286)
				)
			)
		)
		(property "Value" "Single FPGA Conn"
			(at 9.25452 3.621231 270)
			(unlocked yes)
			(layer "F.SilkS")
			(hide yes)
			(effects
				(font
					(size 0.762 0.762)
					(thickness 0.2286)
				)
			)
		)
		(sheetname "FPGA")
		(sheetfile "FPGA.kicad_sch")
		(duplicate_pad_numbers_are_jumpers no)
		(fp_line
			(start -1.40005 1.24993)
			(end -1.40005 0.70002)
			(stroke
				(width 0.15011)
				(type solid)
			)
			(layer "F.SilkS")
		)
		(fp_line
			(start 1.40004 1.24993)
			(end -1.40005 1.24993)
			(stroke
				(width 0.15011)
				(type solid)
			)
			(layer "F.SilkS")
		)
		(fp_line
			(start 1.40004 1.24993)
			(end 1.99999 0.70002)
			(stroke
				(width 0.15011)
				(type solid)
			)
			(layer "F.SilkS")
		)
		(fp_line
			(start -2 0.70002)
			(end -2 0.03302)
			(stroke
				(width 0.15011)
				(type solid)
			)
			(layer "F.SilkS")
		)
		(fp_line
			(start -1.40005 0.70002)
			(end -2 0.70002)
			(stroke
				(width 0.15011)
				(type solid)
			)
			(layer "F.SilkS")
		)
		(fp_line
			(start 1.99999 0.70002)
			(end 1.99999 0.03302)
			(stroke
				(width 0.15011)
				(type solid)
			)
			(layer "F.SilkS")
		)
		(fp_line
			(start -2 -20.03298)
			(end -2 -20.69999)
			(stroke
				(width 0.15011)
				(type solid)
			)
			(layer "F.SilkS")
		)
		(fp_line
			(start 1.99999 -20.03298)
			(end 1.99999 -20.69999)
			(stroke
				(width 0.15011)
				(type solid)
			)
			(layer "F.SilkS")
		)
		(fp_line
			(start -1.40005 -20.69999)
			(end -2 -20.69999)
			(stroke
				(width 0.15011)
				(type solid)
			)
			(layer "F.SilkS")
		)
		(fp_line
			(start -1.40005 -20.69999)
			(end -1.40005 -21.2499)
			(stroke
				(width 0.15011)
				(type solid)
			)
			(layer "F.SilkS")
		)
		(fp_line
			(start 1.99999 -20.69999)
			(end 1.40004 -21.2499)
			(stroke
				(width 0.15011)
				(type solid)
			)
			(layer "F.SilkS")
		)
		(fp_line
			(start 1.40004 -21.2499)
			(end -1.40005 -21.2499)
			(stroke
				(width 0.15011)
				(type solid)
			)
			(layer "F.SilkS")
		)
		(fp_circle
			(center 3.5052 -0.22454)
			(end 3.30505 -0.22454)
			(stroke
				(width 0.40005)
				(type solid)
			)
			(fill no)
			(layer "F.SilkS")
		)
		(pad "1" smd rect
			(at 2.02488 -0.24994 270)
			(size 1.54991 0.24994)
			(layers "F.Cu" "F.Mask" "F.Paste")
			(net "GPS1_PIN15")
		)
		(pad "2" smd rect
			(at -2.02489 -0.24994 270)
			(size 1.54991 0.24994)
			(layers "F.Cu" "F.Mask" "F.Paste")
			(net "GPS1_PIN13")
		)
		(pad "3" smd rect
			(at 2.02488 -0.75007 270)
			(size 1.54991 0.24994)
			(layers "F.Cu" "F.Mask" "F.Paste")
			(net "GPS1_PIN14")
		)
		(pad "4" smd rect
			(at -2.02489 -0.75007 270)
			(size 1.54991 0.24994)
			(layers "F.Cu" "F.Mask" "F.Paste")
			(net "GPS1_PIN11")
		)
		(pad "5" smd rect
			(at 2.02488 -1.24994 270)
			(size 1.54991 0.24994)
			(layers "F.Cu" "F.Mask" "F.Paste")
			(net "GPS1_PIN12")
		)
		(pad "6" smd rect
			(at -2.02489 -1.24994 270)
			(size 1.54991 0.24994)
			(layers "F.Cu" "F.Mask" "F.Paste")
		)
		(pad "7" smd rect
			(at 2.02488 -1.75006 270)
			(size 1.54991 0.24994)
			(layers "F.Cu" "F.Mask" "F.Paste")
		)
		(pad "8" smd rect
			(at -2.02489 -1.75006 270)
			(size 1.54991 0.24994)
			(layers "F.Cu" "F.Mask" "F.Paste")
			(net "MAC_USB_PWR")
		)
		(pad "9" smd rect
			(at 2.02488 -2.24994 270)
			(size 1.54991 0.24994)
			(layers "F.Cu" "F.Mask" "F.Paste")
			(net "GND")
		)
		(pad "10" smd rect
			(at -2.02489 -2.24994 270)
			(size 1.54991 0.24994)
			(layers "F.Cu" "F.Mask" "F.Paste")
			(net "GND")
		)
		(pad "11" smd rect
			(at 2.02488 -2.75006 270)
			(size 1.54991 0.24994)
			(layers "F.Cu" "F.Mask" "F.Paste")
			(net "MAC_RF_OUT")
		)
		(pad "12" smd rect
			(at -2.02489 -2.75006 270)
			(size 1.54991 0.24994)
			(layers "F.Cu" "F.Mask" "F.Paste")
		)
		(pad "13" smd rect
			(at 2.02488 -3.24993 270)
			(size 1.54991 0.24994)
			(layers "F.Cu" "F.Mask" "F.Paste")
			(net "MAC_RF_OUT")
		)
		(pad "14" smd rect
			(at -2.02489 -3.24993 270)
			(size 1.54991 0.24994)
			(layers "F.Cu" "F.Mask" "F.Paste")
		)
		(pad "15" smd rect
			(at 2.02488 -3.75006 270)
			(size 1.54991 0.24994)
			(layers "F.Cu" "F.Mask" "F.Paste")
			(net "ANT1_OUT")
		)
		(pad "16" smd rect
			(at -2.02489 -3.75006 270)
			(size 1.54991 0.24994)
			(layers "F.Cu" "F.Mask" "F.Paste")
			(net "ANT3_IN")
		)
		(pad "17" smd rect
			(at 2.02488 -4.24993 270)
			(size 1.54991 0.24994)
			(layers "F.Cu" "F.Mask" "F.Paste")
			(net "ANT2_OUT")
		)
		(pad "18" smd rect
			(at -2.02489 -4.24993 270)
			(size 1.54991 0.24994)
			(layers "F.Cu" "F.Mask" "F.Paste")
			(net "ANT4_IN")
		)
		(pad "19" smd rect
			(at 2.02488 -4.75006 270)
			(size 1.54991 0.24994)
			(layers "F.Cu" "F.Mask" "F.Paste")
			(net "GND")
		)
		(pad "20" smd rect
			(at -2.02489 -4.75006 270)
			(size 1.54991 0.24994)
			(layers "F.Cu" "F.Mask" "F.Paste")
			(net "GND")
		)
		(pad "21" smd rect
			(at 2.02488 -5.24993 270)
			(size 1.54991 0.24994)
			(layers "F.Cu" "F.Mask" "F.Paste")
			(net "ANT1_IN")
		)
		(pad "22" smd rect
			(at -2.02489 -5.24993 270)
			(size 1.54991 0.24994)
			(layers "F.Cu" "F.Mask" "F.Paste")
		)
		(pad "23" smd rect
			(at 2.02488 -5.75006 270)
			(size 1.54991 0.24994)
			(layers "F.Cu" "F.Mask" "F.Paste")
			(net "ANT2_IN")
		)
		(pad "24" smd rect
			(at -2.02489 -5.75006 270)
			(size 1.54991 0.24994)
			(layers "F.Cu" "F.Mask" "F.Paste")
		)
		(pad "25" smd rect
			(at 2.02488 -6.24993 270)
			(size 1.54991 0.24994)
			(layers "F.Cu" "F.Mask" "F.Paste")
			(net "ANT3_OUT")
		)
		(pad "26" smd rect
			(at -2.02489 -6.24993 270)
			(size 1.54991 0.24994)
			(layers "F.Cu" "F.Mask" "F.Paste")
			(net "MAC_TX")
		)
		(pad "27" smd rect
			(at 2.02488 -6.75005 270)
			(size 1.54991 0.24994)
			(layers "F.Cu" "F.Mask" "F.Paste")
			(net "ANT4_OUT")
		)
		(pad "28" smd rect
			(at -2.02489 -6.75005 270)
			(size 1.54991 0.24994)
			(layers "F.Cu" "F.Mask" "F.Paste")
			(net "MAC_RX")
		)
		(pad "29" smd rect
			(at 2.02488 -7.24993 270)
			(size 1.54991 0.24994)
			(layers "F.Cu" "F.Mask" "F.Paste")
			(net "GND")
		)
		(pad "30" smd rect
			(at -2.02489 -7.24993 270)
			(size 1.54991 0.24994)
			(layers "F.Cu" "F.Mask" "F.Paste")
			(net "GND")
		)
		(pad "31" smd rect
			(at 2.02488 -7.75005 270)
			(size 1.54991 0.24994)
			(layers "F.Cu" "F.Mask" "F.Paste")
		)
		(pad "32" smd rect
			(at -2.02489 -7.75005 270)
			(size 1.54991 0.24994)
			(layers "F.Cu" "F.Mask" "F.Paste")
		)
		(pad "33" smd rect
			(at 2.02488 -8.24992 270)
			(size 1.54991 0.24994)
			(layers "F.Cu" "F.Mask" "F.Paste")
			(net "NetJ35_33")
		)
		(pad "34" smd rect
			(at -2.02489 -8.24992 270)
			(size 1.54991 0.24994)
			(layers "F.Cu" "F.Mask" "F.Paste")
		)
		(pad "35" smd rect
			(at 2.02488 -8.75005 270)
			(size 1.54991 0.24994)
			(layers "F.Cu" "F.Mask" "F.Paste")
			(net "MAC_ALARM")
		)
		(pad "36" smd rect
			(at -2.02489 -8.75005 270)
			(size 1.54991 0.24994)
			(layers "F.Cu" "F.Mask" "F.Paste")
		)
		(pad "37" smd rect
			(at 2.02488 -9.24992 270)
			(size 1.54991 0.24994)
			(layers "F.Cu" "F.Mask" "F.Paste")
			(net "MAC_BITE")
		)
		(pad "38" smd rect
			(at -2.02489 -9.24992 270)
			(size 1.54991 0.24994)
			(layers "F.Cu" "F.Mask" "F.Paste")
		)
		(pad "39" smd rect
			(at 2.02488 -9.75005 270)
			(size 1.54991 0.24994)
			(layers "F.Cu" "F.Mask" "F.Paste")
			(net "GND")
		)
		(pad "40" smd rect
			(at -2.02489 -9.75005 270)
			(size 1.54991 0.24994)
			(layers "F.Cu" "F.Mask" "F.Paste")
			(net "GND")
		)
		(pad "41" smd rect
			(at 2.02488 -10.24992 270)
			(size 1.54991 0.24994)
			(layers "F.Cu" "F.Mask" "F.Paste")
		)
		(pad "42" smd rect
			(at -2.02489 -10.24992 270)
			(size 1.54991 0.24994)
			(layers "F.Cu" "F.Mask" "F.Paste")
		)
		(pad "43" smd rect
			(at 2.02488 -10.75005 270)
			(size 1.54991 0.24994)
			(layers "F.Cu" "F.Mask" "F.Paste")
			(net "FPGA_MAC_PPS_OUT-")
		)
		(pad "44" smd rect
			(at -2.02489 -10.75005 270)
			(size 1.54991 0.24994)
			(layers "F.Cu" "F.Mask" "F.Paste")
		)
		(pad "45" smd rect
			(at 2.02488 -11.24992 270)
			(size 1.54991 0.24994)
			(layers "F.Cu" "F.Mask" "F.Paste")
		)
		(pad "46" smd rect
			(at -2.02489 -11.24992 270)
			(size 1.54991 0.24994)
			(layers "F.Cu" "F.Mask" "F.Paste")
		)
		(pad "47" smd rect
			(at 2.02488 -11.75004 270)
			(size 1.54991 0.24994)
			(layers "F.Cu" "F.Mask" "F.Paste")
			(net "FPGA_MAC_PPS_IN0-")
		)
		(pad "48" smd rect
			(at -2.02489 -11.75004 270)
			(size 1.54991 0.24994)
			(layers "F.Cu" "F.Mask" "F.Paste")
		)
		(pad "49" smd rect
			(at 2.02488 -12.24992 270)
			(size 1.54991 0.24994)
			(layers "F.Cu" "F.Mask" "F.Paste")
			(net "GND")
		)
		(pad "50" smd rect
			(at -2.02489 -12.24992 270)
			(size 1.54991 0.24994)
			(layers "F.Cu" "F.Mask" "F.Paste")
			(net "GND")
		)
		(pad "51" smd rect
			(at 2.02488 -12.75004 270)
			(size 1.54991 0.24994)
			(layers "F.Cu" "F.Mask" "F.Paste")
		)
		(pad "52" smd rect
			(at -2.02489 -12.75004 270)
			(size 1.54991 0.24994)
			(layers "F.Cu" "F.Mask" "F.Paste")
		)
		(pad "53" smd rect
			(at 2.02488 -13.24991 270)
			(size 1.54991 0.24994)
			(layers "F.Cu" "F.Mask" "F.Paste")
			(net "FPGA_MAC_PPS_IN1-")
		)
		(pad "54" smd rect
			(at -2.02489 -13.24991 270)
			(size 1.54991 0.24994)
			(layers "F.Cu" "F.Mask" "F.Paste")
		)
		(pad "55" smd rect
			(at 2.02488 -13.75004 270)
			(size 1.54991 0.24994)
			(layers "F.Cu" "F.Mask" "F.Paste")
			(net "BNO_XIN32_C")
		)
		(pad "56" smd rect
			(at -2.02489 -13.75004 270)
			(size 1.54991 0.24994)
			(layers "F.Cu" "F.Mask" "F.Paste")
		)
		(pad "57" smd rect
			(at 2.02488 -14.24991 270)
			(size 1.54991 0.24994)
			(layers "F.Cu" "F.Mask" "F.Paste")
			(net "BNO_XOUT32_C")
		)
		(pad "58" smd rect
			(at -2.02489 -14.24991 270)
			(size 1.54991 0.24994)
			(layers "F.Cu" "F.Mask" "F.Paste")
		)
		(pad "59" smd rect
			(at 2.02488 -14.75004 270)
			(size 1.54991 0.24994)
			(layers "F.Cu" "F.Mask" "F.Paste")
			(net "GND")
		)
		(pad "60" smd rect
			(at -2.02489 -14.75004 270)
			(size 1.54991 0.24994)
			(layers "F.Cu" "F.Mask" "F.Paste")
			(net "GND")
		)
		(pad "61" smd rect
			(at 2.02488 -15.24991 270)
			(size 1.54991 0.24994)
			(layers "F.Cu" "F.Mask" "F.Paste")
			(net "SDA")
		)
		(pad "62" smd rect
			(at -2.02489 -15.24991 270)
			(size 1.54991 0.24994)
			(layers "F.Cu" "F.Mask" "F.Paste")
		)
		(pad "63" smd rect
			(at 2.02488 -15.75004 270)
			(size 1.54991 0.24994)
			(layers "F.Cu" "F.Mask" "F.Paste")
			(net "BNO_INT")
		)
		(pad "64" smd rect
			(at -2.02489 -15.75004 270)
			(size 1.54991 0.24994)
			(layers "F.Cu" "F.Mask" "F.Paste")
		)
		(pad "65" smd rect
			(at 2.02488 -16.24991 270)
			(size 1.54991 0.24994)
			(layers "F.Cu" "F.Mask" "F.Paste")
			(net "GPS2_PIN15")
		)
		(pad "66" smd rect
			(at -2.02489 -16.24991 270)
			(size 1.54991 0.24994)
			(layers "F.Cu" "F.Mask" "F.Paste")
		)
		(pad "67" smd rect
			(at 2.02488 -16.75003 270)
			(size 1.54991 0.24994)
			(layers "F.Cu" "F.Mask" "F.Paste")
			(net "SCL")
		)
		(pad "68" smd rect
			(at -2.02489 -16.75003 270)
			(size 1.54991 0.24994)
			(layers "F.Cu" "F.Mask" "F.Paste")
		)
		(pad "69" smd rect
			(at 2.02488 -17.24991 270)
			(size 1.54991 0.24994)
			(layers "F.Cu" "F.Mask" "F.Paste")
			(net "GND")
		)
		(pad "70" smd rect
			(at -2.02489 -17.24991 270)
			(size 1.54991 0.24994)
			(layers "F.Cu" "F.Mask" "F.Paste")
			(net "GND")
		)
		(pad "71" smd rect
			(at 2.02488 -17.75003 270)
			(size 1.54991 0.24994)
			(layers "F.Cu" "F.Mask" "F.Paste")
			(net "UART1_TXD")
		)
		(pad "72" smd rect
			(at -2.02489 -17.75003 270)
			(size 1.54991 0.24994)
			(layers "F.Cu" "F.Mask" "F.Paste")
			(net "MAC_USB+")
		)
		(pad "73" smd rect
			(at 2.02488 -18.2499 270)
			(size 1.54991 0.24994)
			(layers "F.Cu" "F.Mask" "F.Paste")
			(net "GPS2_PIN13")
		)
		(pad "74" smd rect
			(at -2.02489 -18.2499 270)
			(size 1.54991 0.24994)
			(layers "F.Cu" "F.Mask" "F.Paste")
			(net "MAC_USB-")
		)
		(pad "75" smd rect
			(at 2.02488 -18.75003 270)
			(size 1.54991 0.24994)
			(layers "F.Cu" "F.Mask" "F.Paste")
			(net "GPS2_PIN11")
		)
		(pad "76" smd rect
			(at -2.02489 -18.75003 270)
			(size 1.54991 0.24994)
			(layers "F.Cu" "F.Mask" "F.Paste")
			(net "GPS2_PIN12")
		)
		(pad "77" smd rect
			(at 2.02488 -19.2499 270)
			(size 1.54991 0.24994)
			(layers "F.Cu" "F.Mask" "F.Paste")
			(net "UART1_RXD")
		)
		(pad "78" smd rect
			(at -2.02489 -19.2499 270)
			(size 1.54991 0.24994)
			(layers "F.Cu" "F.Mask" "F.Paste")
			(net "GPS2_PIN14")
		)
		(pad "79" smd rect
			(at 2.02488 -19.75003 270)
			(size 1.54991 0.24994)
			(layers "F.Cu" "F.Mask" "F.Paste")
			(net "GPS1_RX")
		)
		(pad "80" smd rect
			(at -2.02489 -19.75003 270)
			(size 1.54991 0.24994)
			(layers "F.Cu" "F.Mask" "F.Paste")
			(net "GPS1_TX")
		)
		(pad "81" smd rect
			(at 0.01135 1.17625 270)
			(size 1.70002 1.35001)
			(layers "F.Cu" "F.Mask" "F.Paste")
		)
		(pad "82" thru_hole circle
			(at 0 0 270)
			(size 0.55016 0.55016)
			(drill 0.55016)
			(layers "*.Cu" "*.Mask")
			(remove_unused_layers no)
			(thermal_bridge_angle 90)
		)
		(pad "83" thru_hole circle
			(at 0 -19.99996 270)
			(size 0.55016 0.55016)
			(drill 0.55016)
			(layers "*.Cu" "*.Mask")
			(remove_unused_layers no)
			(thermal_bridge_angle 90)
		)
		(pad "84" smd rect
			(at 0.01135 -21.17375 270)
			(size 1.70002 1.35001)
			(layers "F.Cu" "F.Mask" "F.Paste")
		)
	)
	(footprint "Vault:RESC1005X40X25LL05T05"
		(layer "F.Cu")
		(at 183.4261 86.1162 90)
		(property "Reference" "R56"
			(at -0.3714 -1.073069 90)
			(unlocked yes)
			(layer "F.SilkS")
			(effects
				(font
					(size 0.762 0.762)
					(thickness 0.2286)
				)
			)
		)
		(property "Value" "DNI_4.7K_0402"
			(at -3.151351 5.29409 0)
			(unlocked yes)
			(layer "F.SilkS")
			(hide yes)
			(effects
				(font
					(size 0.762 0.762)
					(thickness 0.2286)
				)
			)
		)
		(sheetname "GPS_IMU_SENSORS")
		(sheetfile "GPS_IMU_SENSORS.kicad_sch")
		(duplicate_pad_numbers_are_jumpers no)
		(pad "1" smd rect
			(at -0.4 0 180)
			(size 0.45 0.45)
			(layers "F.Cu" "F.Mask" "F.Paste")
			(net "GND")
		)
		(pad "2" smd rect
			(at 0.4 0 180)
			(size 0.45 0.45)
			(layers "F.Cu" "F.Mask" "F.Paste")
			(net "NetR53_1")
		)
	)
	(footprint "Vault:FP-CC0603-DA-MFG"
		(layer "F.Cu")
		(at 215.3261 116.0162 -90)
		(property "Reference" "C9"
			(at 4.2 -0.493345 90)
			(unlocked yes)
			(layer "F.SilkS")
			(effects
				(font
					(size 0.762 0.762)
					(thickness 0.2286)
				)
				(justify left bottom)
			)
		)
		(property "Value" "0.1uF_50V_0603"
			(at 5.939845 3.6529 0)
			(unlocked yes)
			(layer "F.SilkS")
			(hide yes)
			(effects
				(font
					(size 0.762 0.762)
					(thickness 0.2286)
				)
				(justify left bottom)
			)
		)
		(sheetname "POWER")
		(sheetfile "POWER.kicad_sch")
		(duplicate_pad_numbers_are_jumpers no)
		(fp_line
			(start 0.85 0.85)
			(end -0.85 0.85)
			(stroke
				(width 0.2)
				(type solid)
			)
			(layer "F.SilkS")
		)
		(fp_line
			(start 0.85 -0.85)
			(end -0.85 -0.85)
			(stroke
				(width 0.2)
				(type solid)
			)
			(layer "F.SilkS")
		)
		(fp_line
			(start -1.35 0.75)
			(end -1.35 -0.75)
			(stroke
				(width 0.2)
				(type solid)
			)
			(layer "F.CrtYd")
		)
		(fp_line
			(start 1.35 0.75)
			(end -1.35 0.75)
			(stroke
				(width 0.2)
				(type solid)
			)
			(layer "F.CrtYd")
		)
		(fp_line
			(start 1.35 0.75)
			(end 1.35 -0.75)
			(stroke
				(width 0.2)
				(type solid)
			)
			(layer "F.CrtYd")
		)
		(fp_line
			(start 1.35 -0.75)
			(end -1.35 -0.75)
			(stroke
				(width 0.2)
				(type solid)
			)
			(layer "F.CrtYd")
		)
		(fp_line
			(start -1.35 0.75)
			(end -1.35 -0.75)
			(stroke
				(width 0.2)
				(type solid)
			)
			(layer "F.Fab")
		)
		(fp_line
			(start 1.35 0.75)
			(end -1.35 0.75)
			(stroke
				(width 0.2)
				(type solid)
			)
			(layer "F.Fab")
		)
		(fp_line
			(start 1.35 0.75)
			(end 1.35 -0.75)
			(stroke
				(width 0.2)
				(type solid)
			)
			(layer "F.Fab")
		)
		(fp_line
			(start 0 0.5)
			(end 0 -0.5)
			(stroke
				(width 0.1)
				(type solid)
			)
			(layer "F.Fab")
		)
		(fp_line
			(start 0.5 0)
			(end -0.5 0)
			(stroke
				(width 0.1)
				(type solid)
			)
			(layer "F.Fab")
		)
		(fp_line
			(start 1.35 -0.75)
			(end -1.35 -0.75)
			(stroke
				(width 0.2)
				(type solid)
			)
			(layer "F.Fab")
		)
		(fp_text user "${REFERENCE}"
			(at -0.00001 0.09602 270)
			(unlocked yes)
			(layer "F.Fab")
			(effects
				(font
					(face "Arial")
					(size 0.63 0.63)
					(thickness 0.1)
				)
				(justify left bottom)
			)
		)
		(pad "1" smd rect
			(at -0.75 0 270)
			(size 0.8 0.9)
			(layers "F.Cu" "F.Mask" "F.Paste")
			(net "NetC9_1")
			(solder_mask_margin 0)
			(solder_paste_margin 0)
		)
		(pad "2" smd rect
			(at 0.75 0 270)
			(size 0.8 0.9)
			(layers "F.Cu" "F.Mask" "F.Paste")
			(net "P5V_FB")
			(solder_mask_margin 0)
			(solder_paste_margin 0)
		)
	)
)
